(kicad_pcb
	(version 20260206)
	(generator "pcbnew")
	(generator_version "10.0")
	(general
		(thickness 1.6)
		(legacy_teardrops no)
	)
	(paper "A4")
	(title_block
		(title "Bryce Canyon_IOM_M2_16342-2_OCP.brd")
		(comment 1 "Bryce Canyon / footprints 250-257 of 1146")
	)
	(layers
		(0 "F.Cu" signal "TOP")
		(4 "In1.Cu" signal "L2GND")
		(6 "In2.Cu" signal "L3")
		(8 "In3.Cu" signal "L4VCC")
		(10 "In4.Cu" signal "L5VCC")
		(12 "In5.Cu" signal "L6")
		(14 "In6.Cu" signal "L7GND")
		(2 "B.Cu" signal "BOTTOM")
		(9 "F.Adhes" user "F.Adhesive")
		(11 "B.Adhes" user "B.Adhesive")
		(13 "F.Paste" user "Package Geometry/Pastemask Top")
		(15 "B.Paste" user "Package Geometry/Pastemask Bottom")
		(5 "F.SilkS" user "Ref Des/Silkscreen Top")
		(7 "B.SilkS" user "Ref Des/Silkscreen Bottom")
		(1 "F.Mask" user "Board Geometry/Soldermask Top")
		(3 "B.Mask" user "Board Geometry/Soldermask Bottom")
		(17 "Dwgs.User" user "User.Drawings")
		(19 "Cmts.User" user "User.Comments")
		(21 "Eco1.User" user "User.Eco1")
		(23 "Eco2.User" user "User.Eco2")
		(25 "Edge.Cuts" user "Board Geometry/Outline")
		(27 "Margin" user)
		(31 "F.CrtYd" user "Package Geometry/Place Bound Top")
		(29 "B.CrtYd" user "Package Geometry/Place Bound Bottom")
		(35 "F.Fab" user "Ref Des/Assembly Top")
		(33 "B.Fab" user "Ref Des/Assembly Bottom")
	)
	(footprint ""
		(layer "F.Cu")
		(at 128.112774 -6.400546)
		(property "Reference" "C146"
			(at 0 0 0)
			(layer "F.SilkS")
			(hide yes)
			(effects
				(font
					(size 1.27 1.27)
				)
			)
		)
		(property "Value" "SCD033U50V3KX-1GP"
			(at 0 -2.8194 0)
			(unlocked yes)
			(layer "F.Fab")
			(hide yes)
			(effects
				(font
					(size 1.016 1.016)
					(thickness 0.1524)
				)
			)
		)
		(property "Device Type" "C603H36"
			(at 0 -4.3434 0)
			(unlocked yes)
			(layer "F.Fab")
			(hide yes)
			(effects
				(font
					(size 1.016 1.016)
					(thickness 0.1524)
				)
			)
		)
		(duplicate_pad_numbers_are_jumpers no)
		(fp_line
			(start 0.508 0)
			(end -0.508 0)
			(stroke
				(width 0.2032)
				(type default)
			)
			(layer "F.SilkS")
		)
		(fp_rect
			(start -0.5842 1.3335)
			(end 0.5842 -1.3335)
			(stroke
				(width 0)
				(type default)
			)
			(fill no)
			(layer "F.CrtYd")
		)
		(fp_rect
			(start -0.5842 1.3335)
			(end 0.5842 -1.3335)
			(stroke
				(width 0)
				(type default)
			)
			(fill no)
			(layer "F.Fab")
		)
		(pad "1" smd custom
			(at 0 -0.762)
			(size 0.2159 0.2159)
			(layers "F.Cu" "F.Mask" "F.Paste")
			(net "MB0_CM_GATE_2")
			(options
				(clearance outline)
				(anchor circle)
			)
			(primitives
				(gr_poly
					(pts
						(arc
							(start -0.3302 -0.4318)
							(mid -0.402042 -0.402042)
							(end -0.4318 -0.3302)
						)
						(arc
							(start -0.4318 0.3302)
							(mid -0.402042 0.402042)
							(end -0.3302 0.4318)
						)
						(arc
							(start 0.3302 0.4318)
							(mid 0.402042 0.402042)
							(end 0.4318 0.3302)
						)
						(arc
							(start 0.4318 -0.3302)
							(mid 0.402042 -0.402042)
							(end 0.3302 -0.4318)
						)
					)
					(width 0)
					(fill yes)
				)
			)
		)
		(pad "2" smd custom
			(at 0 0.762)
			(size 0.2159 0.2159)
			(layers "F.Cu" "F.Mask" "F.Paste")
			(net "GND")
			(options
				(clearance outline)
				(anchor circle)
			)
			(primitives
				(gr_poly
					(pts
						(arc
							(start -0.3302 -0.4318)
							(mid -0.402042 -0.402042)
							(end -0.4318 -0.3302)
						)
						(arc
							(start -0.4318 0.3302)
							(mid -0.402042 0.402042)
							(end -0.3302 0.4318)
						)
						(arc
							(start 0.3302 0.4318)
							(mid 0.402042 0.402042)
							(end 0.4318 0.3302)
						)
						(arc
							(start 0.4318 -0.3302)
							(mid 0.402042 -0.402042)
							(end 0.3302 -0.4318)
						)
					)
					(width 0)
					(fill yes)
				)
			)
		)
	)
	(footprint ""
		(layer "F.Cu")
		(at 75.81138 -186.683396 180)
		(property "Reference" "C199"
			(at 0 0 180)
			(layer "F.SilkS")
			(hide yes)
			(effects
				(font
					(size 1.27 1.27)
				)
			)
		)
		(property "Value" "SC10U6D3V5KX-4GP"
			(at -0.0762 -6.1214 180)
			(unlocked yes)
			(layer "F.Fab")
			(hide yes)
			(effects
				(font
					(size 1.016 1.016)
					(thickness 0.1524)
				)
			)
		)
		(property "Device Type" "C805H58"
			(at -0.0762 -8.1534 180)
			(unlocked yes)
			(layer "F.Fab")
			(hide yes)
			(effects
				(font
					(size 1.016 1.016)
					(thickness 0.1524)
				)
			)
		)
		(duplicate_pad_numbers_are_jumpers no)
		(fp_line
			(start 0.635 0)
			(end -0.635 0)
			(stroke
				(width 0.508)
				(type default)
			)
			(layer "F.SilkS")
		)
		(fp_rect
			(start -0.9652 1.778)
			(end 0.9652 -1.778)
			(stroke
				(width 0)
				(type default)
			)
			(fill no)
			(layer "F.CrtYd")
		)
		(fp_poly
			(pts
				(xy -0.9652 -1.778) (xy 0.9652 -1.778) (xy 0.9652 1.778) (xy -0.9652 1.778)
			)
			(stroke
				(width 0)
				(type default)
			)
			(fill no)
			(layer "F.Fab")
		)
		(pad "1" smd rect
			(at 0 -0.9652 180)
			(size 1.397 1.143)
			(layers "F.Cu" "F.Mask" "F.Paste")
			(net "P3V3_STBY")
		)
		(pad "2" smd rect
			(at 0 0.9652 180)
			(size 1.397 1.143)
			(layers "F.Cu" "F.Mask" "F.Paste")
			(net "GND")
		)
	)
	(footprint ""
		(layer "F.Cu")
		(at 192.405 -139.573 -135)
		(property "Reference" "VIA57"
			(at 0 0 225)
			(layer "F.SilkS")
			(hide yes)
			(effects
				(font
					(size 1.27 1.27)
				)
			)
		)
		(property "Value" "85OHM-8L-1D6MM-L16L18-GP"
			(at 4.064105 0.609655 225)
			(unlocked yes)
			(layer "F.Fab")
			(hide yes)
			(effects
				(font
					(size 1.016 1.016)
					(thickness 0.1524)
				)
			)
		)
		(property "Device Type" "VIA-PCIE-4P-368076"
			(at 4.064105 -0.914474 225)
			(unlocked yes)
			(layer "F.Fab")
			(hide yes)
			(effects
				(font
					(size 1.016 1.016)
					(thickness 0.1524)
				)
			)
		)
		(duplicate_pad_numbers_are_jumpers no)
		(fp_poly
			(pts
				(xy -1.841491 -0.381057) (xy 1.841509 -0.381058) (xy 1.841508 0.380942) (xy -1.841491 0.380942)
			)
			(stroke
				(width 0)
				(type default)
			)
			(fill no)
			(layer "F.CrtYd")
		)
		(fp_poly
			(pts
				(xy -1.841491 -0.381057) (xy 1.841509 -0.381058) (xy 1.841508 0.380942) (xy -1.841491 0.380942)
			)
			(stroke
				(width 0)
				(type default)
			)
			(fill no)
			(layer "F.Fab")
		)
		(pad "1" thru_hole circle
			(at -1.460499 0 225)
			(size 0.508 0.508)
			(drill 0.254)
			(layers "*.Cu" "*.Mask")
			(remove_unused_layers no)
			(net "GND")
			(clearance 0.127)
			(thermal_gap 0.127)
		)
		(pad "2" thru_hole circle
			(at -0.4445 0 225)
			(size 0.508 0.508)
			(drill 0.254)
			(layers "*.Cu" "*.Mask")
			(remove_unused_layers no)
			(net "PCIE_IOM_TO_COMP_11_DP")
			(clearance 0.127)
			(thermal_gap 0.127)
		)
		(pad "3" thru_hole circle
			(at 0.4445 0 225)
			(size 0.508 0.508)
			(drill 0.254)
			(layers "*.Cu" "*.Mask")
			(remove_unused_layers no)
			(net "PCIE_IOM_TO_COMP_11_DN")
			(clearance 0.127)
			(thermal_gap 0.127)
		)
		(pad "4" thru_hole circle
			(at 1.460499 0 225)
			(size 0.508 0.508)
			(drill 0.254)
			(layers "*.Cu" "*.Mask")
			(remove_unused_layers no)
			(net "GND")
			(clearance 0.127)
			(thermal_gap 0.127)
		)
	)
	(footprint ""
		(layer "F.Cu")
		(at 67.8434 -170.2054 180)
		(property "Reference" "C35"
			(at 0 0 180)
			(layer "F.SilkS")
			(hide yes)
			(effects
				(font
					(size 1.27 1.27)
				)
			)
		)
		(property "Value" "SC1U16V2KX-7-GP"
			(at 1.7526 -1.6002 180)
			(unlocked yes)
			(layer "F.Fab")
			(hide yes)
			(effects
				(font
					(size 1.016 1.016)
					(thickness 0.1524)
				)
			)
		)
		(property "Device Type" "C402-TO0D2H24"
			(at 1.7526 -3.1242 180)
			(unlocked yes)
			(layer "F.Fab")
			(hide yes)
			(effects
				(font
					(size 1.016 1.016)
					(thickness 0.1524)
				)
			)
		)
		(duplicate_pad_numbers_are_jumpers no)
		(fp_rect
			(start -0.4826 0.889)
			(end 0.4826 -0.889)
			(stroke
				(width 0)
				(type default)
			)
			(fill no)
			(layer "F.CrtYd")
		)
		(fp_rect
			(start -0.4826 0.889)
			(end 0.4826 -0.889)
			(stroke
				(width 0)
				(type default)
			)
			(fill no)
			(layer "F.Fab")
		)
		(pad "1" smd custom
			(at 0 -0.4572 180)
			(size 0.1524 0.1524)
			(layers "F.Cu" "F.Mask" "F.Paste")
			(net "BMC_SELF_HW_RST_D")
			(options
				(clearance outline)
				(anchor circle)
			)
			(primitives
				(gr_poly
					(pts
						(arc
							(start -0.254 0.3048)
							(mid -0.325842 0.275042)
							(end -0.3556 0.2032)
						)
						(arc
							(start -0.3556 -0.2032)
							(mid -0.325842 -0.275042)
							(end -0.254 -0.3048)
						)
						(arc
							(start 0.254 -0.3048)
							(mid 0.325842 -0.275042)
							(end 0.3556 -0.2032)
						)
						(arc
							(start 0.3556 0.2032)
							(mid 0.325842 0.275042)
							(end 0.254 0.3048)
						)
					)
					(width 0)
					(fill yes)
				)
			)
		)
		(pad "2" smd custom
			(at 0 0.4572 180)
			(size 0.1524 0.1524)
			(layers "F.Cu" "F.Mask" "F.Paste")
			(net "Q4_G")
			(options
				(clearance outline)
				(anchor circle)
			)
			(primitives
				(gr_poly
					(pts
						(arc
							(start -0.254 0.3048)
							(mid -0.325842 0.275042)
							(end -0.3556 0.2032)
						)
						(arc
							(start -0.3556 -0.2032)
							(mid -0.325842 -0.275042)
							(end -0.254 -0.3048)
						)
						(arc
							(start 0.254 -0.3048)
							(mid 0.325842 -0.275042)
							(end 0.3556 -0.2032)
						)
						(arc
							(start 0.3556 0.2032)
							(mid 0.325842 0.275042)
							(end 0.254 0.3048)
						)
					)
					(width 0)
					(fill yes)
				)
			)
		)
	)
	(footprint ""
		(layer "F.Cu")
		(at 112.856264 -9.689338 -90)
		(property "Reference" "R462"
			(at 0 0 270)
			(layer "F.SilkS")
			(hide yes)
			(effects
				(font
					(size 1.27 1.27)
				)
			)
		)
		(property "Value" "22K6R2F-1-GP"
			(at 0.064008 -3.993896 270)
			(unlocked yes)
			(layer "F.Fab")
			(hide yes)
			(effects
				(font
					(size 1.016 1.016)
					(thickness 0.1524)
				)
			)
		)
		(property "Device Type" "R402H16"
			(at 0.064008 -5.517896 270)
			(unlocked yes)
			(layer "F.Fab")
			(hide yes)
			(effects
				(font
					(size 1.016 1.016)
					(thickness 0.1524)
				)
			)
		)
		(duplicate_pad_numbers_are_jumpers no)
		(fp_line
			(start -0.508 -0.9398)
			(end -0.508 0.9398)
			(stroke
				(width 0.1524)
				(type default)
			)
			(layer "F.SilkS")
		)
		(fp_line
			(start 0.508 -0.9398)
			(end -0.508 -0.9398)
			(stroke
				(width 0.1524)
				(type default)
			)
			(layer "F.SilkS")
		)
		(fp_rect
			(start -0.508 0.9398)
			(end 0.508 -0.9398)
			(stroke
				(width 0)
				(type default)
			)
			(fill no)
			(layer "F.CrtYd")
		)
		(fp_rect
			(start -0.508 0.9398)
			(end 0.508 -0.9398)
			(stroke
				(width 0)
				(type default)
			)
			(fill no)
			(layer "F.Fab")
		)
		(pad "1" smd custom
			(at 0 -0.4445 270)
			(size 0.1397 0.1397)
			(layers "F.Cu" "F.Mask" "F.Paste")
			(net "MB0_ISTART_R")
			(options
				(clearance outline)
				(anchor circle)
			)
			(primitives
				(gr_poly
					(pts
						(arc
							(start -0.1778 -0.2794)
							(mid -0.249642 -0.249642)
							(end -0.2794 -0.1778)
						)
						(arc
							(start -0.2794 0.1778)
							(mid -0.249642 0.249642)
							(end -0.1778 0.2794)
						)
						(arc
							(start 0.1778 0.2794)
							(mid 0.249642 0.249642)
							(end 0.2794 0.1778)
						)
						(arc
							(start 0.2794 -0.1778)
							(mid 0.249642 -0.249642)
							(end 0.1778 -0.2794)
						)
					)
					(width 0)
					(fill yes)
				)
			)
		)
		(pad "2" smd custom
			(at 0 0.4445 270)
			(size 0.1397 0.1397)
			(layers "F.Cu" "F.Mask" "F.Paste")
			(net "AGND_CURRENT_MON")
			(options
				(clearance outline)
				(anchor circle)
			)
			(primitives
				(gr_poly
					(pts
						(arc
							(start -0.1778 -0.2794)
							(mid -0.249642 -0.249642)
							(end -0.2794 -0.1778)
						)
						(arc
							(start -0.2794 0.1778)
							(mid -0.249642 0.249642)
							(end -0.1778 0.2794)
						)
						(arc
							(start 0.1778 0.2794)
							(mid 0.249642 0.249642)
							(end 0.2794 0.1778)
						)
						(arc
							(start 0.2794 -0.1778)
							(mid 0.249642 -0.249642)
							(end 0.1778 -0.2794)
						)
					)
					(width 0)
					(fill yes)
				)
			)
		)
	)
	(footprint ""
		(layer "F.Cu")
		(at 27.800046 -186.56681 180)
		(property "Reference" "C176"
			(at 0 0 180)
			(layer "F.SilkS")
			(hide yes)
			(effects
				(font
					(size 1.27 1.27)
				)
			)
		)
		(property "Value" "SC10U16V5KX-7-GP-U"
			(at -0.0762 -6.1214 180)
			(unlocked yes)
			(layer "F.Fab")
			(hide yes)
			(effects
				(font
					(size 1.016 1.016)
					(thickness 0.1524)
				)
			)
		)
		(property "Device Type" "C805H58"
			(at -0.0762 -8.1534 180)
			(unlocked yes)
			(layer "F.Fab")
			(hide yes)
			(effects
				(font
					(size 1.016 1.016)
					(thickness 0.1524)
				)
			)
		)
		(duplicate_pad_numbers_are_jumpers no)
		(fp_line
			(start 0.635 0)
			(end -0.635 0)
			(stroke
				(width 0.508)
				(type default)
			)
			(layer "F.SilkS")
		)
		(fp_rect
			(start -0.9652 1.778)
			(end 0.9652 -1.778)
			(stroke
				(width 0)
				(type default)
			)
			(fill no)
			(layer "F.CrtYd")
		)
		(fp_poly
			(pts
				(xy -0.9652 -1.778) (xy 0.9652 -1.778) (xy 0.9652 1.778) (xy -0.9652 1.778)
			)
			(stroke
				(width 0)
				(type default)
			)
			(fill no)
			(layer "F.Fab")
		)
		(pad "1" smd rect
			(at 0 -0.9652 180)
			(size 1.397 1.143)
			(layers "F.Cu" "F.Mask" "F.Paste")
			(net "P12V_STBY_VIN_PU2")
		)
		(pad "2" smd rect
			(at 0 0.9652 180)
			(size 1.397 1.143)
			(layers "F.Cu" "F.Mask" "F.Paste")
			(net "GND")
		)
	)
	(footprint ""
		(layer "F.Cu")
		(at 10.7442 -139.573 90)
		(property "Reference" "R218"
			(at 0 0 90)
			(layer "F.SilkS")
			(hide yes)
			(effects
				(font
					(size 1.27 1.27)
				)
			)
		)
		(property "Value" "120R2F-GP"
			(at 0.064008 -3.993896 90)
			(unlocked yes)
			(layer "F.Fab")
			(hide yes)
			(effects
				(font
					(size 1.016 1.016)
					(thickness 0.1524)
				)
			)
		)
		(property "Device Type" "R402H16"
			(at 0.064008 -5.517896 90)
			(unlocked yes)
			(layer "F.Fab")
			(hide yes)
			(effects
				(font
					(size 1.016 1.016)
					(thickness 0.1524)
				)
			)
		)
		(duplicate_pad_numbers_are_jumpers no)
		(fp_line
			(start 0.508 -0.9398)
			(end -0.508 -0.9398)
			(stroke
				(width 0.1524)
				(type default)
			)
			(layer "F.SilkS")
		)
		(fp_line
			(start -0.508 -0.9398)
			(end -0.508 0.9398)
			(stroke
				(width 0.1524)
				(type default)
			)
			(layer "F.SilkS")
		)
		(fp_rect
			(start -0.508 0.9398)
			(end 0.508 -0.9398)
			(stroke
				(width 0)
				(type default)
			)
			(fill no)
			(layer "F.CrtYd")
		)
		(fp_rect
			(start -0.508 0.9398)
			(end 0.508 -0.9398)
			(stroke
				(width 0)
				(type default)
			)
			(fill no)
			(layer "F.Fab")
		)
		(pad "1" smd custom
			(at 0 -0.4445 90)
			(size 0.1397 0.1397)
			(layers "F.Cu" "F.Mask" "F.Paste")
			(net "MEMBG_0")
			(options
				(clearance outline)
				(anchor circle)
			)
			(primitives
				(gr_poly
					(pts
						(arc
							(start -0.1778 -0.2794)
							(mid -0.249642 -0.249642)
							(end -0.2794 -0.1778)
						)
						(arc
							(start -0.2794 0.1778)
							(mid -0.249642 0.249642)
							(end -0.1778 0.2794)
						)
						(arc
							(start 0.1778 0.2794)
							(mid 0.249642 0.249642)
							(end 0.2794 0.1778)
						)
						(arc
							(start 0.2794 -0.1778)
							(mid 0.249642 -0.249642)
							(end 0.1778 -0.2794)
						)
					)
					(width 0)
					(fill yes)
				)
			)
		)
		(pad "2" smd custom
			(at 0 0.4445 90)
			(size 0.1397 0.1397)
			(layers "F.Cu" "F.Mask" "F.Paste")
			(net "P1V2_STBY")
			(options
				(clearance outline)
				(anchor circle)
			)
			(primitives
				(gr_poly
					(pts
						(arc
							(start -0.1778 -0.2794)
							(mid -0.249642 -0.249642)
							(end -0.2794 -0.1778)
						)
						(arc
							(start -0.2794 0.1778)
							(mid -0.249642 0.249642)
							(end -0.1778 0.2794)
						)
						(arc
							(start 0.1778 0.2794)
							(mid 0.249642 0.249642)
							(end 0.2794 0.1778)
						)
						(arc
							(start 0.2794 -0.1778)
							(mid 0.249642 -0.249642)
							(end 0.1778 -0.2794)
						)
					)
					(width 0)
					(fill yes)
				)
			)
		)
	)
	(footprint ""
		(layer "F.Cu")
		(at 42.291 -161.417)
		(property "Reference" "R313"
			(at 0 0 0)
			(layer "F.SilkS")
			(hide yes)
			(effects
				(font
					(size 1.27 1.27)
				)
			)
		)
		(property "Value" "4K7R2F-GP"
			(at 0.064008 -3.993896 0)
			(unlocked yes)
			(layer "F.Fab")
			(hide yes)
			(effects
				(font
					(size 1.016 1.016)
					(thickness 0.1524)
				)
			)
		)
		(property "Device Type" "R402H16"
			(at 0.064008 -5.517896 0)
			(unlocked yes)
			(layer "F.Fab")
			(hide yes)
			(effects
				(font
					(size 1.016 1.016)
					(thickness 0.1524)
				)
			)
		)
		(duplicate_pad_numbers_are_jumpers no)
		(fp_line
			(start -0.508 -0.9398)
			(end -0.508 0.9398)
			(stroke
				(width 0.1524)
				(type default)
			)
			(layer "F.SilkS")
		)
		(fp_line
			(start 0.508 -0.9398)
			(end -0.508 -0.9398)
			(stroke
				(width 0.1524)
				(type default)
			)
			(layer "F.SilkS")
		)
		(fp_rect
			(start -0.508 0.9398)
			(end 0.508 -0.9398)
			(stroke
				(width 0)
				(type default)
			)
			(fill no)
			(layer "F.CrtYd")
		)
		(fp_rect
			(start -0.508 0.9398)
			(end 0.508 -0.9398)
			(stroke
				(width 0)
				(type default)
			)
			(fill no)
			(layer "F.Fab")
		)
		(pad "1" smd custom
			(at 0 -0.4445)
			(size 0.1397 0.1397)
			(layers "F.Cu" "F.Mask" "F.Paste")
			(net "GND")
			(options
				(clearance outline)
				(anchor circle)
			)
			(primitives
				(gr_poly
					(pts
						(arc
							(start -0.1778 -0.2794)
							(mid -0.249642 -0.249642)
							(end -0.2794 -0.1778)
						)
						(arc
							(start -0.2794 0.1778)
							(mid -0.249642 0.249642)
							(end -0.1778 0.2794)
						)
						(arc
							(start 0.1778 0.2794)
							(mid 0.249642 0.249642)
							(end 0.2794 0.1778)
						)
						(arc
							(start 0.2794 -0.1778)
							(mid 0.249642 -0.249642)
							(end 0.1778 -0.2794)
						)
					)
					(width 0)
					(fill yes)
				)
			)
		)
		(pad "2" smd custom
			(at 0 0.4445)
			(size 0.1397 0.1397)
			(layers "F.Cu" "F.Mask" "F.Paste")
			(net "BOARD_REV_0")
			(options
				(clearance outline)
				(anchor circle)
			)
			(primitives
				(gr_poly
					(pts
						(arc
							(start -0.1778 -0.2794)
							(mid -0.249642 -0.249642)
							(end -0.2794 -0.1778)
						)
						(arc
							(start -0.2794 0.1778)
							(mid -0.249642 0.249642)
							(end -0.1778 0.2794)
						)
						(arc
							(start 0.1778 0.2794)
							(mid 0.249642 0.249642)
							(end 0.2794 0.1778)
						)
						(arc
							(start 0.2794 -0.1778)
							(mid 0.249642 -0.249642)
							(end 0.1778 -0.2794)
						)
					)
					(width 0)
					(fill yes)
				)
			)
		)
	)
)
